# BARRELEYE_G2-FPDB_POST-PVT-X02-BOM-X05-20171123_Final.xls.xlsx — Component Qual Tracker (bom)
|  |  |  |  |  |  |  |  | Part to be included on following build: |  |  |  |  |  |
| Item No. | Part Group | Single/Sole/Multi | Item Description | ODM P/N | Customer PN | Vendor | Vendor P/N | X00 Build | X01 Build | X02 Build | Qual Build | Qualification Target Date | Qualification Complete Date |
|  | VR Controllers |  |  |  |  | Vendor #1 |  |  |  |  |  |  |  |
|  |  |  |  |  |  | Vendor #2 |  |  |  |  |  |  |  |
|  | FETS |  |  |  |  | Vendor #1 |  |  |  |  |  |  |  |
|  |  |  |  |  |  | Vendor #2 |  |  |  |  |  |  |  |
|  | INDUCTORS |  |  |  |  | Vendor #1 |  |  |  |  |  |  |  |
|  |  |  |  |  |  | Vendor #2 |  |  |  |  |  |  |  |
|  | VREG CAPS |  |  |  |  | Vendor #1 |  |  |  |  |  |  |  |
|  |  |  |  |  |  | Vendor #2 |  |  |  |  |  |  |  |
|  | CRYSTALS |  |  |  |  | Vendor #1 |  |  |  |  |  |  |  |
|  |  |  |  |  |  | Vendor #2 |  |  |  |  |  |  |  |
|  | CONNECTORS |  |  |  |  | Vendor #1 |  |  |  |  |  |  |  |
|  |  |  |  |  |  | Vendor #2 |  |  |  |  |  |  |  |
|  | IC'S |  |  |  |  | Vendor #1 |  |  |  |  |  |  |  |
|  |  |  |  |  |  | Vendor #2 |  |  |  |  |  |  |  |
|  | MISC. |  |  |  |  | Vendor #1 |  |  |  |  |  |  |  |
|  | (HEATSINKS) |  |  |  |  | Vendor #2 |  |  |  |  |  |  |  |
